(kicad_pcb
	(version 20260206)
	(generator "pcbnew")
	(generator_version "10.0")
	(general
		(thickness 1.6)
		(legacy_teardrops no)
	)
	(paper "A4")
	(title_block
		(title "baseboard — 13948-1b.1110WZS1818.brd")
		(comment 1 "Honey Badger (Wiwynn) / footprints 1101-1108 of 2523")
	)
	(layers
		(0 "F.Cu" signal "TOP")
		(4 "In1.Cu" signal "L2GND")
		(6 "In2.Cu" signal "L3")
		(8 "In3.Cu" signal "L4VCC")
		(10 "In4.Cu" signal "L5VCC")
		(12 "In5.Cu" signal "L6")
		(14 "In6.Cu" signal "L7GND")
		(2 "B.Cu" signal "BOTTOM")
		(9 "F.Adhes" user "F.Adhesive")
		(11 "B.Adhes" user "B.Adhesive")
		(13 "F.Paste" user "Package Geometry/Pastemask Top")
		(15 "B.Paste" user "Package Geometry/Pastemask Bottom")
		(5 "F.SilkS" user "Ref Des/Silkscreen Top")
		(7 "B.SilkS" user "Ref Des/Silkscreen Bottom")
		(1 "F.Mask" user "Board Geometry/Soldermask Top")
		(3 "B.Mask" user "Board Geometry/Soldermask Bottom")
		(17 "Dwgs.User" user "User.Drawings")
		(19 "Cmts.User" user "User.Comments")
		(21 "Eco1.User" user "User.Eco1")
		(23 "Eco2.User" user "User.Eco2")
		(25 "Edge.Cuts" user "Board Geometry/Outline")
		(27 "Margin" user)
		(31 "F.CrtYd" user "Package Geometry/Place Bound Top")
		(29 "B.CrtYd" user "Package Geometry/Place Bound Bottom")
		(35 "F.Fab" user "Ref Des/Assembly Top")
		(33 "B.Fab" user "Ref Des/Assembly Bottom")
	)
	(footprint ""
		(layer "F.Cu")
		(at 95.70847 -104.902 -90)
		(property "Reference" "SR793"
			(at 0 0 270)
			(layer "F.SilkS")
			(hide yes)
			(effects
				(font
					(size 1.27 1.27)
				)
			)
		)
		(property "Value" "0R2J-2-GP"
			(at 0.064008 -3.993896 270)
			(unlocked yes)
			(layer "F.Fab")
			(hide yes)
			(effects
				(font
					(size 1.016 1.016)
					(thickness 0.1524)
				)
			)
		)
		(property "Device Type" "R402H16"
			(at 0.064008 -5.517896 270)
			(unlocked yes)
			(layer "F.Fab")
			(hide yes)
			(effects
				(font
					(size 1.016 1.016)
					(thickness 0.1524)
				)
			)
		)
		(duplicate_pad_numbers_are_jumpers no)
		(fp_line
			(start -0.508 -0.9398)
			(end -0.508 0.9398)
			(stroke
				(width 0.1524)
				(type default)
			)
			(layer "F.SilkS")
		)
		(fp_line
			(start 0.508 -0.9398)
			(end -0.508 -0.9398)
			(stroke
				(width 0.1524)
				(type default)
			)
			(layer "F.SilkS")
		)
		(fp_rect
			(start -0.508 0.9398)
			(end 0.508 -0.9398)
			(stroke
				(width 0)
				(type default)
			)
			(fill no)
			(layer "F.CrtYd")
		)
		(fp_rect
			(start -0.508 0.9398)
			(end 0.508 -0.9398)
			(stroke
				(width 0)
				(type default)
			)
			(fill no)
			(layer "F.Fab")
		)
		(pad "1" smd custom
			(at 0 -0.4445 270)
			(size 0.1397 0.1397)
			(layers "F.Cu" "F.Mask" "F.Paste")
			(net "SMART_TX")
			(options
				(clearance outline)
				(anchor circle)
			)
			(primitives
				(gr_poly
					(pts
						(arc
							(start -0.1778 -0.2794)
							(mid -0.249642 -0.249642)
							(end -0.2794 -0.1778)
						)
						(arc
							(start -0.2794 0.1778)
							(mid -0.249642 0.249642)
							(end -0.1778 0.2794)
						)
						(arc
							(start 0.1778 0.2794)
							(mid 0.249642 0.249642)
							(end 0.2794 0.1778)
						)
						(arc
							(start 0.2794 -0.1778)
							(mid 0.249642 -0.249642)
							(end 0.1778 -0.2794)
						)
					)
					(width 0)
					(fill yes)
				)
			)
		)
		(pad "2" smd custom
			(at 0 0.4445 270)
			(size 0.1397 0.1397)
			(layers "F.Cu" "F.Mask" "F.Paste")
			(net "SAS_SMART_TX")
			(options
				(clearance outline)
				(anchor circle)
			)
			(primitives
				(gr_poly
					(pts
						(arc
							(start -0.1778 -0.2794)
							(mid -0.249642 -0.249642)
							(end -0.2794 -0.1778)
						)
						(arc
							(start -0.2794 0.1778)
							(mid -0.249642 0.249642)
							(end -0.1778 0.2794)
						)
						(arc
							(start 0.1778 0.2794)
							(mid 0.249642 0.249642)
							(end 0.2794 0.1778)
						)
						(arc
							(start 0.2794 -0.1778)
							(mid 0.249642 -0.249642)
							(end 0.1778 -0.2794)
						)
					)
					(width 0)
					(fill yes)
				)
			)
		)
	)
	(footprint ""
		(layer "F.Cu")
		(at 298.494958 -58.166 180)
		(property "Reference" "C284"
			(at 0 0 180)
			(layer "F.SilkS")
			(hide yes)
			(effects
				(font
					(size 1.27 1.27)
				)
			)
		)
		(property "Value" "SC1U25V3KX-GP"
			(at 0 -2.8194 180)
			(unlocked yes)
			(layer "F.Fab")
			(hide yes)
			(effects
				(font
					(size 1.016 1.016)
					(thickness 0.1524)
				)
			)
		)
		(property "Device Type" "C603H36"
			(at 0 -4.3434 180)
			(unlocked yes)
			(layer "F.Fab")
			(hide yes)
			(effects
				(font
					(size 1.016 1.016)
					(thickness 0.1524)
				)
			)
		)
		(duplicate_pad_numbers_are_jumpers no)
		(fp_line
			(start 0.508 0)
			(end -0.508 0)
			(stroke
				(width 0.2032)
				(type default)
			)
			(layer "F.SilkS")
		)
		(fp_rect
			(start -0.5842 1.3335)
			(end 0.5842 -1.3335)
			(stroke
				(width 0)
				(type default)
			)
			(fill no)
			(layer "F.CrtYd")
		)
		(fp_rect
			(start -0.5842 1.3335)
			(end 0.5842 -1.3335)
			(stroke
				(width 0)
				(type default)
			)
			(fill no)
			(layer "F.Fab")
		)
		(pad "1" smd custom
			(at 0 -0.762 180)
			(size 0.2159 0.2159)
			(layers "F.Cu" "F.Mask" "F.Paste")
			(net "P3V3_STBY")
			(options
				(clearance outline)
				(anchor circle)
			)
			(primitives
				(gr_poly
					(pts
						(arc
							(start -0.3302 -0.4318)
							(mid -0.402042 -0.402042)
							(end -0.4318 -0.3302)
						)
						(arc
							(start -0.4318 0.3302)
							(mid -0.402042 0.402042)
							(end -0.3302 0.4318)
						)
						(arc
							(start 0.3302 0.4318)
							(mid 0.402042 0.402042)
							(end 0.4318 0.3302)
						)
						(arc
							(start 0.4318 -0.3302)
							(mid 0.402042 -0.402042)
							(end 0.3302 -0.4318)
						)
					)
					(width 0)
					(fill yes)
				)
			)
		)
		(pad "2" smd custom
			(at 0 0.762 180)
			(size 0.2159 0.2159)
			(layers "F.Cu" "F.Mask" "F.Paste")
			(net "GND")
			(options
				(clearance outline)
				(anchor circle)
			)
			(primitives
				(gr_poly
					(pts
						(arc
							(start -0.3302 -0.4318)
							(mid -0.402042 -0.402042)
							(end -0.4318 -0.3302)
						)
						(arc
							(start -0.4318 0.3302)
							(mid -0.402042 0.402042)
							(end -0.3302 0.4318)
						)
						(arc
							(start 0.3302 0.4318)
							(mid 0.402042 0.402042)
							(end 0.4318 0.3302)
						)
						(arc
							(start 0.4318 -0.3302)
							(mid 0.402042 -0.402042)
							(end 0.3302 -0.4318)
						)
					)
					(width 0)
					(fill yes)
				)
			)
		)
	)
	(footprint ""
		(layer "F.Cu")
		(at 39.51097 -134.62 90)
		(property "Reference" "SR857"
			(at 0 0 90)
			(layer "F.SilkS")
			(hide yes)
			(effects
				(font
					(size 1.27 1.27)
				)
			)
		)
		(property "Value" "4K7R2F-GP"
			(at 0.064008 -3.993896 90)
			(unlocked yes)
			(layer "F.Fab")
			(hide yes)
			(effects
				(font
					(size 1.016 1.016)
					(thickness 0.1524)
				)
			)
		)
		(property "Device Type" "R402H16"
			(at 0.064008 -5.517896 90)
			(unlocked yes)
			(layer "F.Fab")
			(hide yes)
			(effects
				(font
					(size 1.016 1.016)
					(thickness 0.1524)
				)
			)
		)
		(duplicate_pad_numbers_are_jumpers no)
		(fp_line
			(start 0.508 -0.9398)
			(end -0.508 -0.9398)
			(stroke
				(width 0.1524)
				(type default)
			)
			(layer "F.SilkS")
		)
		(fp_line
			(start -0.508 -0.9398)
			(end -0.508 0.9398)
			(stroke
				(width 0.1524)
				(type default)
			)
			(layer "F.SilkS")
		)
		(fp_rect
			(start -0.508 0.9398)
			(end 0.508 -0.9398)
			(stroke
				(width 0)
				(type default)
			)
			(fill no)
			(layer "F.CrtYd")
		)
		(fp_rect
			(start -0.508 0.9398)
			(end 0.508 -0.9398)
			(stroke
				(width 0)
				(type default)
			)
			(fill no)
			(layer "F.Fab")
		)
		(pad "1" smd custom
			(at 0 -0.4445 90)
			(size 0.1397 0.1397)
			(layers "F.Cu" "F.Mask" "F.Paste")
			(net "P3V3_STBY")
			(options
				(clearance outline)
				(anchor circle)
			)
			(primitives
				(gr_poly
					(pts
						(arc
							(start -0.1778 -0.2794)
							(mid -0.249642 -0.249642)
							(end -0.2794 -0.1778)
						)
						(arc
							(start -0.2794 0.1778)
							(mid -0.249642 0.249642)
							(end -0.1778 0.2794)
						)
						(arc
							(start 0.1778 0.2794)
							(mid 0.249642 0.249642)
							(end 0.2794 0.1778)
						)
						(arc
							(start 0.2794 -0.1778)
							(mid 0.249642 -0.249642)
							(end 0.1778 -0.2794)
						)
					)
					(width 0)
					(fill yes)
				)
			)
		)
		(pad "2" smd custom
			(at 0 0.4445 90)
			(size 0.1397 0.1397)
			(layers "F.Cu" "F.Mask" "F.Paste")
			(net "P3V3_STBY_R5")
			(options
				(clearance outline)
				(anchor circle)
			)
			(primitives
				(gr_poly
					(pts
						(arc
							(start -0.1778 -0.2794)
							(mid -0.249642 -0.249642)
							(end -0.2794 -0.1778)
						)
						(arc
							(start -0.2794 0.1778)
							(mid -0.249642 0.249642)
							(end -0.1778 0.2794)
						)
						(arc
							(start 0.1778 0.2794)
							(mid 0.249642 0.249642)
							(end 0.2794 0.1778)
						)
						(arc
							(start 0.2794 -0.1778)
							(mid 0.249642 -0.249642)
							(end 0.1778 -0.2794)
						)
					)
					(width 0)
					(fill yes)
				)
			)
		)
	)
	(footprint ""
		(layer "F.Cu")
		(at 345.596718 -157.838648 180)
		(property "Reference" "R553"
			(at 0 0 180)
			(layer "F.SilkS")
			(hide yes)
			(effects
				(font
					(size 1.27 1.27)
				)
			)
		)
		(property "Value" "4K7R2F-GP"
			(at 0.064008 -3.993896 180)
			(unlocked yes)
			(layer "F.Fab")
			(hide yes)
			(effects
				(font
					(size 1.016 1.016)
					(thickness 0.1524)
				)
			)
		)
		(property "Device Type" "R402H16"
			(at 0.064008 -5.517896 180)
			(unlocked yes)
			(layer "F.Fab")
			(hide yes)
			(effects
				(font
					(size 1.016 1.016)
					(thickness 0.1524)
				)
			)
		)
		(duplicate_pad_numbers_are_jumpers no)
		(fp_line
			(start 0.508 -0.9398)
			(end -0.508 -0.9398)
			(stroke
				(width 0.1524)
				(type default)
			)
			(layer "F.SilkS")
		)
		(fp_line
			(start -0.508 -0.9398)
			(end -0.508 0.9398)
			(stroke
				(width 0.1524)
				(type default)
			)
			(layer "F.SilkS")
		)
		(fp_rect
			(start -0.508 0.9398)
			(end 0.508 -0.9398)
			(stroke
				(width 0)
				(type default)
			)
			(fill no)
			(layer "F.CrtYd")
		)
		(fp_rect
			(start -0.508 0.9398)
			(end 0.508 -0.9398)
			(stroke
				(width 0)
				(type default)
			)
			(fill no)
			(layer "F.Fab")
		)
		(pad "1" smd custom
			(at 0 -0.4445 180)
			(size 0.1397 0.1397)
			(layers "F.Cu" "F.Mask" "F.Paste")
			(net "USB_EN_1")
			(options
				(clearance outline)
				(anchor circle)
			)
			(primitives
				(gr_poly
					(pts
						(arc
							(start -0.1778 -0.2794)
							(mid -0.249642 -0.249642)
							(end -0.2794 -0.1778)
						)
						(arc
							(start -0.2794 0.1778)
							(mid -0.249642 0.249642)
							(end -0.1778 0.2794)
						)
						(arc
							(start 0.1778 0.2794)
							(mid 0.249642 0.249642)
							(end 0.2794 0.1778)
						)
						(arc
							(start 0.2794 -0.1778)
							(mid 0.249642 -0.249642)
							(end 0.1778 -0.2794)
						)
					)
					(width 0)
					(fill yes)
				)
			)
		)
		(pad "2" smd custom
			(at 0 0.4445 180)
			(size 0.1397 0.1397)
			(layers "F.Cu" "F.Mask" "F.Paste")
			(net "GND")
			(options
				(clearance outline)
				(anchor circle)
			)
			(primitives
				(gr_poly
					(pts
						(arc
							(start -0.1778 -0.2794)
							(mid -0.249642 -0.249642)
							(end -0.2794 -0.1778)
						)
						(arc
							(start -0.2794 0.1778)
							(mid -0.249642 0.249642)
							(end -0.1778 0.2794)
						)
						(arc
							(start 0.1778 0.2794)
							(mid 0.249642 0.249642)
							(end 0.2794 0.1778)
						)
						(arc
							(start 0.2794 -0.1778)
							(mid 0.249642 -0.249642)
							(end 0.1778 -0.2794)
						)
					)
					(width 0)
					(fill yes)
				)
			)
		)
	)
	(footprint ""
		(layer "F.Cu")
		(at 223.647 -84.963 90)
		(property "Reference" "SR926"
			(at 0 0 90)
			(layer "F.SilkS")
			(hide yes)
			(effects
				(font
					(size 1.27 1.27)
				)
			)
		)
		(property "Value" "0R2J-2-GP"
			(at 0.064008 -3.993896 90)
			(unlocked yes)
			(layer "F.Fab")
			(hide yes)
			(effects
				(font
					(size 1.016 1.016)
					(thickness 0.1524)
				)
			)
		)
		(property "Device Type" "R402H16"
			(at 0.064008 -5.517896 90)
			(unlocked yes)
			(layer "F.Fab")
			(hide yes)
			(effects
				(font
					(size 1.016 1.016)
					(thickness 0.1524)
				)
			)
		)
		(duplicate_pad_numbers_are_jumpers no)
		(fp_line
			(start 0.508 -0.9398)
			(end -0.508 -0.9398)
			(stroke
				(width 0.1524)
				(type default)
			)
			(layer "F.SilkS")
		)
		(fp_line
			(start -0.508 -0.9398)
			(end -0.508 0.9398)
			(stroke
				(width 0.1524)
				(type default)
			)
			(layer "F.SilkS")
		)
		(fp_rect
			(start -0.508 0.9398)
			(end 0.508 -0.9398)
			(stroke
				(width 0)
				(type default)
			)
			(fill no)
			(layer "F.CrtYd")
		)
		(fp_rect
			(start -0.508 0.9398)
			(end 0.508 -0.9398)
			(stroke
				(width 0)
				(type default)
			)
			(fill no)
			(layer "F.Fab")
		)
		(pad "1" smd custom
			(at 0 -0.4445 90)
			(size 0.1397 0.1397)
			(layers "F.Cu" "F.Mask" "F.Paste")
			(net "IOC_UART_0_RX_R")
			(options
				(clearance outline)
				(anchor circle)
			)
			(primitives
				(gr_poly
					(pts
						(arc
							(start -0.1778 -0.2794)
							(mid -0.249642 -0.249642)
							(end -0.2794 -0.1778)
						)
						(arc
							(start -0.2794 0.1778)
							(mid -0.249642 0.249642)
							(end -0.1778 0.2794)
						)
						(arc
							(start 0.1778 0.2794)
							(mid 0.249642 0.249642)
							(end 0.2794 0.1778)
						)
						(arc
							(start 0.2794 -0.1778)
							(mid 0.249642 -0.249642)
							(end 0.1778 -0.2794)
						)
					)
					(width 0)
					(fill yes)
				)
			)
		)
		(pad "2" smd custom
			(at 0 0.4445 90)
			(size 0.1397 0.1397)
			(layers "F.Cu" "F.Mask" "F.Paste")
			(net "IOC_UART_0_RX")
			(options
				(clearance outline)
				(anchor circle)
			)
			(primitives
				(gr_poly
					(pts
						(arc
							(start -0.1778 -0.2794)
							(mid -0.249642 -0.249642)
							(end -0.2794 -0.1778)
						)
						(arc
							(start -0.2794 0.1778)
							(mid -0.249642 0.249642)
							(end -0.1778 0.2794)
						)
						(arc
							(start 0.1778 0.2794)
							(mid 0.249642 0.249642)
							(end 0.2794 0.1778)
						)
						(arc
							(start 0.2794 -0.1778)
							(mid 0.249642 -0.249642)
							(end 0.1778 -0.2794)
						)
					)
					(width 0)
					(fill yes)
				)
			)
		)
	)
	(footprint ""
		(layer "F.Cu")
		(at 86.49716 -35.306 -90)
		(property "Reference" "SC881"
			(at 0 0 270)
			(layer "F.SilkS")
			(hide yes)
			(effects
				(font
					(size 1.27 1.27)
				)
			)
		)
		(property "Value" "SCD01U10V1KX-GP"
			(at -2.8321 -1.7399 270)
			(unlocked yes)
			(layer "F.Fab")
			(hide yes)
			(effects
				(font
					(size 1.016 1.016)
					(thickness 0.1524)
				)
			)
		)
		(property "Device Type" "C0201H13"
			(at -2.8321 -3.2639 270)
			(unlocked yes)
			(layer "F.Fab")
			(hide yes)
			(effects
				(font
					(size 1.016 1.016)
					(thickness 0.1524)
				)
			)
		)
		(duplicate_pad_numbers_are_jumpers no)
		(fp_rect
			(start -0.2794 0.6477)
			(end 0.2794 -0.6477)
			(stroke
				(width 0)
				(type default)
			)
			(fill no)
			(layer "F.CrtYd")
		)
		(fp_rect
			(start -0.2794 0.6477)
			(end 0.2794 -0.6477)
			(stroke
				(width 0)
				(type default)
			)
			(fill no)
			(layer "F.Fab")
		)
		(pad "1" smd custom
			(at 0 -0.2794 270)
			(size 0.0762 0.0762)
			(layers "F.Cu" "F.Mask" "F.Paste")
			(net "SAS3008_RAID_TX_C_P1")
			(options
				(clearance outline)
				(anchor circle)
			)
			(primitives
				(gr_poly
					(pts
						(arc
							(start 0.1524 -0.127)
							(mid 0.137521 -0.162921)
							(end 0.1016 -0.1778)
						)
						(arc
							(start -0.1016 -0.1778)
							(mid -0.137521 -0.162921)
							(end -0.1524 -0.127)
						)
						(arc
							(start -0.1524 0.127)
							(mid -0.137521 0.162921)
							(end -0.1016 0.1778)
						)
						(arc
							(start 0.1016 0.1778)
							(mid 0.137521 0.162921)
							(end 0.1524 0.127)
						)
					)
					(width 0)
					(fill yes)
				)
			)
		)
		(pad "2" smd custom
			(at 0 0.2794 270)
			(size 0.0762 0.0762)
			(layers "F.Cu" "F.Mask" "F.Paste")
			(net "SAS3008_RAID_TX_P1")
			(options
				(clearance outline)
				(anchor circle)
			)
			(primitives
				(gr_poly
					(pts
						(arc
							(start 0.1524 -0.127)
							(mid 0.137521 -0.162921)
							(end 0.1016 -0.1778)
						)
						(arc
							(start -0.1016 -0.1778)
							(mid -0.137521 -0.162921)
							(end -0.1524 -0.127)
						)
						(arc
							(start -0.1524 0.127)
							(mid -0.137521 0.162921)
							(end -0.1016 0.1778)
						)
						(arc
							(start 0.1016 0.1778)
							(mid 0.137521 0.162921)
							(end 0.1524 0.127)
						)
					)
					(width 0)
					(fill yes)
				)
			)
		)
	)
	(footprint ""
		(layer "F.Cu")
		(at 99.45497 -118.3005 180)
		(property "Reference" "SR747"
			(at 0 0 180)
			(layer "F.SilkS")
			(hide yes)
			(effects
				(font
					(size 1.27 1.27)
				)
			)
		)
		(property "Value" "4K7R2F-GP"
			(at 0.064008 -3.993896 180)
			(unlocked yes)
			(layer "F.Fab")
			(hide yes)
			(effects
				(font
					(size 1.016 1.016)
					(thickness 0.1524)
				)
			)
		)
		(property "Device Type" "R402H16"
			(at 0.064008 -5.517896 180)
			(unlocked yes)
			(layer "F.Fab")
			(hide yes)
			(effects
				(font
					(size 1.016 1.016)
					(thickness 0.1524)
				)
			)
		)
		(duplicate_pad_numbers_are_jumpers no)
		(fp_line
			(start 0.508 -0.9398)
			(end -0.508 -0.9398)
			(stroke
				(width 0.1524)
				(type default)
			)
			(layer "F.SilkS")
		)
		(fp_line
			(start -0.508 -0.9398)
			(end -0.508 0.9398)
			(stroke
				(width 0.1524)
				(type default)
			)
			(layer "F.SilkS")
		)
		(fp_rect
			(start -0.508 0.9398)
			(end 0.508 -0.9398)
			(stroke
				(width 0)
				(type default)
			)
			(fill no)
			(layer "F.CrtYd")
		)
		(fp_rect
			(start -0.508 0.9398)
			(end 0.508 -0.9398)
			(stroke
				(width 0)
				(type default)
			)
			(fill no)
			(layer "F.Fab")
		)
		(pad "1" smd custom
			(at 0 -0.4445 180)
			(size 0.1397 0.1397)
			(layers "F.Cu" "F.Mask" "F.Paste")
			(net "SIO_D_IN")
			(options
				(clearance outline)
				(anchor circle)
			)
			(primitives
				(gr_poly
					(pts
						(arc
							(start -0.1778 -0.2794)
							(mid -0.249642 -0.249642)
							(end -0.2794 -0.1778)
						)
						(arc
							(start -0.2794 0.1778)
							(mid -0.249642 0.249642)
							(end -0.1778 0.2794)
						)
						(arc
							(start 0.1778 0.2794)
							(mid 0.249642 0.249642)
							(end 0.2794 0.1778)
						)
						(arc
							(start 0.2794 -0.1778)
							(mid 0.249642 -0.249642)
							(end 0.1778 -0.2794)
						)
					)
					(width 0)
					(fill yes)
				)
			)
		)
		(pad "2" smd custom
			(at 0 0.4445 180)
			(size 0.1397 0.1397)
			(layers "F.Cu" "F.Mask" "F.Paste")
			(net "P1V8_E")
			(options
				(clearance outline)
				(anchor circle)
			)
			(primitives
				(gr_poly
					(pts
						(arc
							(start -0.1778 -0.2794)
							(mid -0.249642 -0.249642)
							(end -0.2794 -0.1778)
						)
						(arc
							(start -0.2794 0.1778)
							(mid -0.249642 0.249642)
							(end -0.1778 0.2794)
						)
						(arc
							(start 0.1778 0.2794)
							(mid 0.249642 0.249642)
							(end 0.2794 0.1778)
						)
						(arc
							(start 0.2794 -0.1778)
							(mid 0.249642 -0.249642)
							(end 0.1778 -0.2794)
						)
					)
					(width 0)
					(fill yes)
				)
			)
		)
	)
	(footprint ""
		(layer "F.Cu")
		(at 97.54997 -86.233)
		(property "Reference" "STP144"
			(at 0 0 0)
			(layer "F.SilkS")
			(hide yes)
			(effects
				(font
					(size 1.27 1.27)
				)
			)
		)
		(property "Value" "TPAD28"
			(at 0.0127 -1.8034 0)
			(unlocked yes)
			(layer "F.Fab")
			(hide yes)
			(effects
				(font
					(size 1.016 1.016)
					(thickness 0.1524)
				)
			)
		)
		(property "Device Type" "TPAD28"
			(at 0.0127 -3.3274 0)
			(unlocked yes)
			(layer "F.Fab")
			(hide yes)
			(effects
				(font
					(size 1.016 1.016)
					(thickness 0.1524)
				)
			)
		)
		(duplicate_pad_numbers_are_jumpers no)
		(fp_poly
			(pts
				(arc
					(start 0.3556 0)
					(mid -0.3556 0)
					(end 0.3556 0)
				)
			)
			(stroke
				(width 0)
				(type default)
			)
			(fill no)
			(layer "F.CrtYd")
		)
		(fp_poly
			(pts
				(arc
					(start 0.6096 0)
					(mid -0.6096 0)
					(end 0.6096 0)
				)
			)
			(stroke
				(width 0)
				(type default)
			)
			(fill no)
			(layer "F.Fab")
		)
		(pad "1" smd circle
			(at 0 0)
			(size 0.7112 0.7112)
			(layers "F.Cu" "F.Mask" "F.Paste")
			(net "SXP_ACTIVE_1")
		)
	)
)
